# T6G (Grand Teton) — schematic netlist excerpt (pin names and nets, part order shuffled) for the footprints in the layout excerpt that follows; sources: Cadence DE-HDL packaged netlist, KiCad conversion of 04192023_DAF0TMB3IC0_F0TG_MB_C_brd_V02_OCP.brd

PR6613  Q_RES  0 5% CHIP  pkg 0402LF  page 362 : A = NC_P0V9_RETIMER_CPU0_IMON7 ; B = GND
D8002  Q_LED  IC  pkg SMLF  page 256 : A = LED_P12V_SCM_FAULT ; C = LED_P12V_SCM_FAULT_D2

(kicad_pcb
	(version 20260206)
	(generator "pcbnew")
	(generator_version "10.0")
	(general
		(thickness 1.6)
		(legacy_teardrops no)
	)
	(paper "A4")
	(title_block
		(title "04192023_DAF0TMB3IC0_F0TG_MB_C_brd_V02_OCP.brd")
		(comment 1 "Grand Teton / footprints 1240-1241 of 8354")
	)
	(layers
		(0 "F.Cu" signal "TOP")
		(4 "In1.Cu" signal "GND")
		(6 "In2.Cu" signal "IN1")
		(8 "In3.Cu" signal "GND1")
		(10 "In4.Cu" signal "IN2")
		(12 "In5.Cu" signal "GND2")
		(14 "In6.Cu" signal "IN3")
		(16 "In7.Cu" signal "GND3")
		(18 "In8.Cu" signal "VCC")
		(20 "In9.Cu" signal "VCC1")
		(22 "In10.Cu" signal "GND4")
		(24 "In11.Cu" signal "IN4")
		(26 "In12.Cu" signal "GND5")
		(28 "In13.Cu" signal "IN5")
		(30 "In14.Cu" signal "GND6")
		(32 "In15.Cu" signal "IN6")
		(34 "In16.Cu" signal "GND7")
		(2 "B.Cu" signal "BOTTOM")
		(9 "F.Adhes" user "F.Adhesive")
		(11 "B.Adhes" user "B.Adhesive")
		(13 "F.Paste" user "Package Geometry/Pastemask Top")
		(15 "B.Paste" user "Package Geometry/Pastemask Bottom")
		(5 "F.SilkS" user "Ref Des/Silkscreen Top")
		(7 "B.SilkS" user "Ref Des/Silkscreen Bottom")
		(1 "F.Mask" user "Board Geometry/Soldermask Top")
		(3 "B.Mask" user "Board Geometry/Soldermask Bottom")
		(17 "Dwgs.User" user "User.Drawings")
		(19 "Cmts.User" user "User.Comments")
		(21 "Eco1.User" user "User.Eco1")
		(23 "Eco2.User" user "User.Eco2")
		(25 "Edge.Cuts" user "Board Geometry/Outline")
		(27 "Margin" user)
		(31 "F.CrtYd" user "Package Geometry/Place Bound Top")
		(29 "B.CrtYd" user "Package Geometry/Place Bound Bottom")
		(35 "F.Fab" user "Ref Des/Assembly Top")
		(33 "B.Fab" user "Ref Des/Assembly Bottom")
	)
	(footprint ""
		(layer "F.Cu")
		(at 446.522602 -418.96411 -90)
		(property "Reference" "PR6613"
			(at 0 0 270)
			(layer "F.SilkS")
			(hide yes)
			(effects
				(font
					(size 1.27 1.27)
				)
			)
		)
		(property "Value" ""
			(at 0 0 270)
			(layer "F.Fab")
			(effects
				(font
					(size 1.27 1.27)
				)
			)
		)
		(duplicate_pad_numbers_are_jumpers no)
		(fp_line
			(start -0.7874 0.4064)
			(end -0.7874 -0.4064)
			(stroke
				(width 0.1524)
				(type default)
			)
			(layer "F.SilkS")
		)
		(fp_line
			(start 0.7874 0.4064)
			(end -0.7874 0.4064)
			(stroke
				(width 0.1524)
				(type default)
			)
			(layer "F.SilkS")
		)
		(fp_line
			(start -0.7874 -0.4064)
			(end 0.7874 -0.4064)
			(stroke
				(width 0.1524)
				(type default)
			)
			(layer "F.SilkS")
		)
		(fp_line
			(start 0.7874 -0.4064)
			(end 0.7874 0.4064)
			(stroke
				(width 0.1524)
				(type default)
			)
			(layer "F.SilkS")
		)
		(fp_line
			(start -0.67945 0.3048)
			(end -0.67945 -0.305054)
			(stroke
				(width 0.1)
				(type default)
			)
			(layer "F.Fab")
		)
		(fp_line
			(start -0.12065 0.3048)
			(end -0.67945 0.3048)
			(stroke
				(width 0.1)
				(type default)
			)
			(layer "F.Fab")
		)
		(fp_line
			(start 0.120396 0.3048)
			(end 0.120396 0.2794)
			(stroke
				(width 0.1)
				(type default)
			)
			(layer "F.Fab")
		)
		(fp_line
			(start 0.67945 0.3048)
			(end 0.120396 0.3048)
			(stroke
				(width 0.1)
				(type default)
			)
			(layer "F.Fab")
		)
		(fp_line
			(start -0.12065 0.2794)
			(end -0.12065 0.3048)
			(stroke
				(width 0.1)
				(type default)
			)
			(layer "F.Fab")
		)
		(fp_line
			(start 0.120396 0.2794)
			(end -0.12065 0.2794)
			(stroke
				(width 0.1)
				(type default)
			)
			(layer "F.Fab")
		)
		(fp_line
			(start -0.12065 -0.2794)
			(end 0.12065 -0.2794)
			(stroke
				(width 0.1)
				(type default)
			)
			(layer "F.Fab")
		)
		(fp_line
			(start 0.12065 -0.2794)
			(end 0.12065 -0.3048)
			(stroke
				(width 0.1)
				(type default)
			)
			(layer "F.Fab")
		)
		(fp_line
			(start 0.12065 -0.3048)
			(end 0.67945 -0.3048)
			(stroke
				(width 0.1)
				(type default)
			)
			(layer "F.Fab")
		)
		(fp_line
			(start 0.67945 -0.3048)
			(end 0.67945 0.3048)
			(stroke
				(width 0.1)
				(type default)
			)
			(layer "F.Fab")
		)
		(fp_line
			(start -0.67945 -0.305054)
			(end -0.12065 -0.305054)
			(stroke
				(width 0.1)
				(type default)
			)
			(layer "F.Fab")
		)
		(fp_line
			(start -0.12065 -0.305054)
			(end -0.12065 -0.2794)
			(stroke
				(width 0.1)
				(type default)
			)
			(layer "F.Fab")
		)
		(pad "1" smd circle
			(at -0.40005 0 270)
			(size 0 0)
			(layers "F.Cu" "F.Mask" "F.Paste")
			(net "NC_P0V9_RETIMER_CPU0_IMON7")
		)
		(pad "2" smd circle
			(at 0.40005 0 270)
			(size 0 0)
			(layers "F.Cu" "F.Mask" "F.Paste")
			(net "GND")
		)
	)
	(footprint ""
		(layer "F.Cu")
		(at 191.389 -50.673 90)
		(property "Reference" "D8002"
			(at -2.191004 -3.142488 90)
			(unlocked yes)
			(layer "F.SilkS")
			(effects
				(font
					(size 0.7874 0.5842)
					(thickness 0.1524)
				)
				(justify left)
			)
		)
		(property "Value" ""
			(at 0 0 90)
			(layer "F.Fab")
			(effects
				(font
					(size 1.27 1.27)
				)
			)
		)
		(duplicate_pad_numbers_are_jumpers no)
		(fp_line
			(start 1.778 -0.5588)
			(end 1.3208 -0.5588)
			(stroke
				(width 0.1524)
				(type default)
			)
			(layer "F.SilkS")
		)
		(fp_line
			(start 1.778 -0.5588)
			(end 1.778 0.5588)
			(stroke
				(width 0.1524)
				(type default)
			)
			(layer "F.SilkS")
		)
		(fp_line
			(start 1.4732 -0.5588)
			(end 1.4732 0.5588)
			(stroke
				(width 0.1524)
				(type default)
			)
			(layer "F.SilkS")
		)
		(fp_line
			(start 1.3208 -0.5588)
			(end 1.3208 0.5588)
			(stroke
				(width 0.1524)
				(type default)
			)
			(layer "F.SilkS")
		)
		(fp_line
			(start -1.3208 -0.5588)
			(end 1.3208 -0.5588)
			(stroke
				(width 0.1524)
				(type default)
			)
			(layer "F.SilkS")
		)
		(fp_line
			(start 1.778 0.5588)
			(end 1.3208 0.5588)
			(stroke
				(width 0.1524)
				(type default)
			)
			(layer "F.SilkS")
		)
		(fp_line
			(start 1.6256 0.5588)
			(end 1.6256 -0.5588)
			(stroke
				(width 0.1524)
				(type default)
			)
			(layer "F.SilkS")
		)
		(fp_line
			(start 1.3208 0.5588)
			(end -1.3208 0.5588)
			(stroke
				(width 0.1524)
				(type default)
			)
			(layer "F.SilkS")
		)
		(fp_line
			(start -1.3208 0.5588)
			(end -1.3208 -0.5588)
			(stroke
				(width 0.1524)
				(type default)
			)
			(layer "F.SilkS")
		)
		(fp_line
			(start 0.899922 -0.40005)
			(end 0.899922 0.40005)
			(stroke
				(width 0.1)
				(type default)
			)
			(layer "F.Fab")
		)
		(fp_line
			(start -0.899922 -0.40005)
			(end 0.899922 -0.40005)
			(stroke
				(width 0.1)
				(type default)
			)
			(layer "F.Fab")
		)
		(fp_line
			(start 0.899922 0.40005)
			(end -0.899922 0.40005)
			(stroke
				(width 0.1)
				(type default)
			)
			(layer "F.Fab")
		)
		(fp_line
			(start -0.899922 0.40005)
			(end -0.899922 -0.40005)
			(stroke
				(width 0.1)
				(type default)
			)
			(layer "F.Fab")
		)
		(fp_text user "+"
			(at -2.6162 -0.22225 90)
			(unlocked yes)
			(layer "F.SilkS")
			(effects
				(font
					(size 1.905 1.4224)
					(thickness 0.1524)
				)
				(justify left)
			)
		)
		(fp_text user "-"
			(at 1.73101 0.59436 90)
			(unlocked yes)
			(layer "F.SilkS")
			(effects
				(font
					(size 1.905 1.4224)
					(thickness 0.1524)
				)
				(justify left)
			)
		)
		(fp_text user "-"
			(at 1.651 -0.22225 90)
			(unlocked yes)
			(layer "F.Fab")
			(effects
				(font
					(size 1.905 1.4224)
					(thickness 0.1524)
				)
				(justify left)
			)
		)
		(fp_text user "+"
			(at -2.6162 -0.22225 90)
			(unlocked yes)
			(layer "F.Fab")
			(effects
				(font
					(size 1.905 1.4224)
					(thickness 0.1524)
				)
				(justify left)
			)
		)
		(pad "A" smd rect
			(at -0.750062 0 90)
			(size 0.8128 0.8128)
			(layers "F.Cu" "F.Mask" "F.Paste")
			(net "LED_P12V_SCM_FAULT")
		)
		(pad "C" smd rect
			(at 0.750062 0 90)
			(size 0.8128 0.8128)
			(layers "F.Cu" "F.Mask" "F.Paste")
			(net "LED_P12V_SCM_FAULT_D2")
		)
	)
)
